(kicad_pcb
	(version 20260206)
	(generator "pcbnew")
	(generator_version "10.0")
	(general
		(thickness 1.6)
		(legacy_teardrops no)
	)
	(paper "A4")
	(title_block
		(title "Wiwynn_Tioga_Pass_MB.brd")
		(comment 1 "Tioga Pass / footprints 4664-4670 of 4770")
	)
	(layers
		(0 "F.Cu" signal "TOP")
		(4 "In1.Cu" signal "L2GND")
		(6 "In2.Cu" signal "L3")
		(8 "In3.Cu" signal "L4GND")
		(10 "In4.Cu" signal "L5")
		(12 "In5.Cu" signal "L6GND")
		(14 "In6.Cu" signal "L7VCC")
		(16 "In7.Cu" signal "L8VCC")
		(18 "In8.Cu" signal "L9GND")
		(20 "In9.Cu" signal "L10")
		(22 "In10.Cu" signal "L11GND")
		(24 "In11.Cu" signal "L12")
		(26 "In12.Cu" signal "L13GND")
		(2 "B.Cu" signal "BOTTOM")
		(9 "F.Adhes" user "F.Adhesive")
		(11 "B.Adhes" user "B.Adhesive")
		(13 "F.Paste" user "Package Geometry/Pastemask Top")
		(15 "B.Paste" user "Package Geometry/Pastemask Bottom")
		(5 "F.SilkS" user "Ref Des/Silkscreen Top")
		(7 "B.SilkS" user "Ref Des/Silkscreen Bottom")
		(1 "F.Mask" user "Board Geometry/Soldermask Top")
		(3 "B.Mask" user "Board Geometry/Soldermask Bottom")
		(17 "Dwgs.User" user "User.Drawings")
		(19 "Cmts.User" user "User.Comments")
		(21 "Eco1.User" user "User.Eco1")
		(23 "Eco2.User" user "User.Eco2")
		(25 "Edge.Cuts" user "Board Geometry/Outline")
		(27 "Margin" user)
		(31 "F.CrtYd" user "Package Geometry/Place Bound Top")
		(29 "B.CrtYd" user "Package Geometry/Place Bound Bottom")
		(35 "F.Fab" user "Ref Des/Assembly Top")
		(33 "B.Fab" user "Ref Des/Assembly Bottom")
	)
	(footprint ""
		(layer "B.Cu")
		(at 419.4175 -6.589014 180)
		(property "Reference" "U7D3"
			(at 1.60147 1.397 270)
			(unlocked yes)
			(layer "B.SilkS")
			(effects
				(font
					(size 0.7874 0.5842)
					(thickness 0.1524)
				)
				(justify mirror)
			)
		)
		(property "Value" ""
			(at 0 0 0)
			(layer "B.Fab")
			(effects
				(font
					(size 1.27 1.27)
				)
				(justify mirror)
			)
		)
		(duplicate_pad_numbers_are_jumpers no)
		(fp_line
			(start -0.760222 1.75006)
			(end -1.146048 1.75006)
			(stroke
				(width 0.1524)
				(type default)
			)
			(layer "B.SilkS")
		)
		(fp_line
			(start -1.146048 -0.450088)
			(end -0.760222 -0.450088)
			(stroke
				(width 0.1524)
				(type default)
			)
			(layer "B.SilkS")
		)
		(fp_circle
			(center 1.194054 -0.610362)
			(end 1.067054 -0.610362)
			(stroke
				(width 0.254)
				(type default)
			)
			(fill no)
			(layer "B.SilkS")
		)
		(fp_poly
			(pts
				(xy -0.277622 -0.450088) (xy -0.277622 1.75006) (xy -1.627378 1.75006) (xy -1.627378 -0.450088)
			)
			(stroke
				(width 0)
				(type default)
			)
			(fill no)
			(layer "B.CrtYd")
		)
		(fp_line
			(start -0.277622 1.75006)
			(end -0.277622 -0.450088)
			(stroke
				(width 0.1)
				(type default)
			)
			(layer "B.Fab")
		)
		(fp_line
			(start -0.277622 -0.450088)
			(end -1.627378 -0.450088)
			(stroke
				(width 0.1)
				(type default)
			)
			(layer "B.Fab")
		)
		(fp_line
			(start -1.627378 1.75006)
			(end -0.277622 1.75006)
			(stroke
				(width 0.1)
				(type default)
			)
			(layer "B.Fab")
		)
		(fp_line
			(start -1.627378 -0.450088)
			(end -1.627378 1.75006)
			(stroke
				(width 0.1)
				(type default)
			)
			(layer "B.Fab")
		)
		(fp_circle
			(center 1.194054 -0.610362)
			(end 1.067054 -0.610362)
			(stroke
				(width 0.254)
				(type default)
			)
			(fill no)
			(layer "B.Fab")
		)
		(pad "1" smd rect
			(at 0 0)
			(size 1.016 0.4064)
			(layers "B.Cu" "B.Mask" "B.Paste")
			(net "PWRGD_P3V3_STBY")
		)
		(pad "2" smd rect
			(at 0 0.649986)
			(size 1.016 0.4064)
			(layers "B.Cu" "B.Mask" "B.Paste")
			(net "GND")
		)
		(pad "3" smd rect
			(at 0 1.299972)
			(size 1.016 0.4064)
			(layers "B.Cu" "B.Mask" "B.Paste")
			(net "VSENSE_P12V_ADM1085")
		)
		(pad "4" smd rect
			(at -1.905 1.299972)
			(size 1.016 0.4064)
			(layers "B.Cu" "B.Mask" "B.Paste")
			(net "PWRGD_DSW_PWROK")
		)
		(pad "5" smd rect
			(at -1.905 0.649986)
			(size 1.016 0.4064)
			(layers "B.Cu" "B.Mask" "B.Paste")
			(net "A_ADM1085_CEXT")
		)
		(pad "6" smd rect
			(at -1.905 0)
			(size 1.016 0.4064)
			(layers "B.Cu" "B.Mask" "B.Paste")
			(net "P3V3_STBY")
		)
	)
	(footprint ""
		(layer "B.Cu")
		(at 80.731868 -3.3528 -90)
		(property "Reference" "C5G87"
			(at -1.14681 0.76708 0)
			(unlocked yes)
			(layer "B.SilkS")
			(effects
				(font
					(size 0.7874 0.5842)
					(thickness 0.1524)
				)
				(justify mirror)
			)
		)
		(property "Value" ""
			(at 0 0 90)
			(layer "B.Fab")
			(effects
				(font
					(size 1.27 1.27)
				)
				(justify mirror)
			)
		)
		(duplicate_pad_numbers_are_jumpers no)
		(fp_rect
			(start 0.4953 1.6002)
			(end -0.4953 -0.2032)
			(stroke
				(width 0)
				(type default)
			)
			(fill no)
			(layer "B.CrtYd")
		)
		(fp_line
			(start -0.4953 1.6002)
			(end 0.4953 1.6002)
			(stroke
				(width 0.1)
				(type default)
			)
			(layer "B.Fab")
		)
		(fp_line
			(start 0.4953 1.6002)
			(end 0.4953 -0.2032)
			(stroke
				(width 0.1)
				(type default)
			)
			(layer "B.Fab")
		)
		(fp_line
			(start -0.4953 -0.2032)
			(end -0.4953 1.6002)
			(stroke
				(width 0.1)
				(type default)
			)
			(layer "B.Fab")
		)
		(fp_line
			(start 0.4953 -0.2032)
			(end -0.4953 -0.2032)
			(stroke
				(width 0.1)
				(type default)
			)
			(layer "B.Fab")
		)
		(pad "1" smd rect
			(at 0 0 90)
			(size 0.762 0.889)
			(layers "B.Cu" "B.Mask" "B.Paste")
			(net "PVDDQ_GHJ")
		)
		(pad "2" smd rect
			(at 0 1.397 90)
			(size 0.762 0.889)
			(layers "B.Cu" "B.Mask" "B.Paste")
			(net "GND")
		)
		(zone
			(layer "B.Cu")
			(hatch none 0.5)
			(connect_pads
				(clearance 0)
			)
			(min_thickness 0.25)
			(keepout
				(tracks not_allowed)
				(vias allowed)
				(pads allowed)
				(copperpour not_allowed)
				(footprints allowed)
			)
			(placement
				(enabled no)
				(sheetname "")
			)
			(fill
				(thermal_gap 0.5)
				(thermal_bridge_width 0.5)
				(island_removal_mode 0)
			)
			(polygon
				(pts
					(xy 79.779368 -2.9718) (xy 80.287368 -2.9718) (xy 80.287368 -3.7338) (xy 79.779368 -3.7338)
				)
			)
		)
	)
	(footprint ""
		(layer "B.Cu")
		(at 252.1585 -135.4074 -90)
		(property "Reference" "C5M5"
			(at -1.848866 0.752348 270)
			(unlocked yes)
			(layer "B.SilkS")
			(effects
				(font
					(size 1.27 0.9652)
					(thickness 0.1524)
				)
				(justify mirror)
			)
		)
		(property "Value" ""
			(at 0 0 90)
			(layer "B.Fab")
			(effects
				(font
					(size 1.27 1.27)
				)
				(justify mirror)
			)
		)
		(duplicate_pad_numbers_are_jumpers no)
		(fp_rect
			(start 0.500126 1.598422)
			(end -0.500126 -0.201422)
			(stroke
				(width 0)
				(type default)
			)
			(fill no)
			(layer "B.CrtYd")
		)
		(fp_line
			(start -0.500126 1.598422)
			(end 0.500126 1.598422)
			(stroke
				(width 0.1)
				(type default)
			)
			(layer "B.Fab")
		)
		(fp_line
			(start 0.500126 1.598422)
			(end 0.500126 -0.201422)
			(stroke
				(width 0.1)
				(type default)
			)
			(layer "B.Fab")
		)
		(fp_line
			(start -0.500126 -0.201422)
			(end -0.500126 1.598422)
			(stroke
				(width 0.1)
				(type default)
			)
			(layer "B.Fab")
		)
		(fp_line
			(start 0.500126 -0.201422)
			(end -0.500126 -0.201422)
			(stroke
				(width 0.1)
				(type default)
			)
			(layer "B.Fab")
		)
		(pad "1" smd rect
			(at 0 0 180)
			(size 0.889 0.9906)
			(layers "B.Cu" "B.Mask" "B.Paste")
			(net "PVDDQ_DEF")
		)
		(pad "2" smd rect
			(at 0 1.397 180)
			(size 0.889 0.9906)
			(layers "B.Cu" "B.Mask" "B.Paste")
			(net "GND")
		)
		(zone
			(layer "B.Cu")
			(hatch none 0.5)
			(connect_pads
				(clearance 0)
			)
			(min_thickness 0.25)
			(keepout
				(tracks not_allowed)
				(vias allowed)
				(pads allowed)
				(copperpour not_allowed)
				(footprints allowed)
			)
			(placement
				(enabled no)
				(sheetname "")
			)
			(fill
				(thermal_gap 0.5)
				(thermal_bridge_width 0.5)
				(island_removal_mode 0)
			)
			(polygon
				(pts
					(xy 251.206 -134.9121) (xy 251.714 -134.9121) (xy 251.714 -135.9027) (xy 251.206 -135.9027)
				)
			)
		)
		(zone
			(layer "B.Cu")
			(hatch none 0.5)
			(connect_pads
				(clearance 0)
			)
			(min_thickness 0.25)
			(keepout
				(tracks allowed)
				(vias not_allowed)
				(pads allowed)
				(copperpour not_allowed)
				(footprints allowed)
			)
			(placement
				(enabled no)
				(sheetname "")
			)
			(fill
				(thermal_gap 0.5)
				(thermal_bridge_width 0.5)
				(island_removal_mode 0)
			)
			(polygon
				(pts
					(xy 251.206 -134.9121) (xy 251.714 -134.9121) (xy 251.714 -135.9027) (xy 251.206 -135.9027)
				)
			)
		)
	)
	(footprint ""
		(layer "B.Cu")
		(at 83.856068 -17.7546 -90)
		(property "Reference" "C8T9"
			(at -1.848866 0.752348 270)
			(unlocked yes)
			(layer "B.SilkS")
			(effects
				(font
					(size 1.27 0.9652)
					(thickness 0.1524)
				)
				(justify mirror)
			)
		)
		(property "Value" ""
			(at 0 0 90)
			(layer "B.Fab")
			(effects
				(font
					(size 1.27 1.27)
				)
				(justify mirror)
			)
		)
		(duplicate_pad_numbers_are_jumpers no)
		(fp_rect
			(start 0.500126 1.598422)
			(end -0.500126 -0.201422)
			(stroke
				(width 0)
				(type default)
			)
			(fill no)
			(layer "B.CrtYd")
		)
		(fp_line
			(start -0.500126 1.598422)
			(end 0.500126 1.598422)
			(stroke
				(width 0.1)
				(type default)
			)
			(layer "B.Fab")
		)
		(fp_line
			(start 0.500126 1.598422)
			(end 0.500126 -0.201422)
			(stroke
				(width 0.1)
				(type default)
			)
			(layer "B.Fab")
		)
		(fp_line
			(start -0.500126 -0.201422)
			(end -0.500126 1.598422)
			(stroke
				(width 0.1)
				(type default)
			)
			(layer "B.Fab")
		)
		(fp_line
			(start 0.500126 -0.201422)
			(end -0.500126 -0.201422)
			(stroke
				(width 0.1)
				(type default)
			)
			(layer "B.Fab")
		)
		(pad "1" smd rect
			(at 0 0 180)
			(size 0.889 0.9906)
			(layers "B.Cu" "B.Mask" "B.Paste")
			(net "PVDDQ_GHJ")
		)
		(pad "2" smd rect
			(at 0 1.397 180)
			(size 0.889 0.9906)
			(layers "B.Cu" "B.Mask" "B.Paste")
			(net "GND")
		)
		(zone
			(layer "B.Cu")
			(hatch none 0.5)
			(connect_pads
				(clearance 0)
			)
			(min_thickness 0.25)
			(keepout
				(tracks allowed)
				(vias not_allowed)
				(pads allowed)
				(copperpour not_allowed)
				(footprints allowed)
			)
			(placement
				(enabled no)
				(sheetname "")
			)
			(fill
				(thermal_gap 0.5)
				(thermal_bridge_width 0.5)
				(island_removal_mode 0)
			)
			(polygon
				(pts
					(xy 82.903568 -17.2593) (xy 83.411568 -17.2593) (xy 83.411568 -18.2499) (xy 82.903568 -18.2499)
				)
			)
		)
		(zone
			(layer "B.Cu")
			(hatch none 0.5)
			(connect_pads
				(clearance 0)
			)
			(min_thickness 0.25)
			(keepout
				(tracks not_allowed)
				(vias allowed)
				(pads allowed)
				(copperpour not_allowed)
				(footprints allowed)
			)
			(placement
				(enabled no)
				(sheetname "")
			)
			(fill
				(thermal_gap 0.5)
				(thermal_bridge_width 0.5)
				(island_removal_mode 0)
			)
			(polygon
				(pts
					(xy 82.903568 -17.2593) (xy 83.411568 -17.2593) (xy 83.411568 -18.2499) (xy 82.903568 -18.2499)
				)
			)
		)
	)
	(footprint ""
		(layer "B.Cu")
		(at 473.130118 -134.958074 -90)
		(property "Reference" "C1W19"
			(at 0.8382 -0.67818 270)
			(unlocked yes)
			(layer "B.SilkS")
			(effects
				(font
					(size 0.4064 0.254)
					(thickness 0.1524)
				)
				(justify left mirror)
			)
		)
		(property "Value" ""
			(at 0 0 90)
			(layer "B.Fab")
			(effects
				(font
					(size 1.27 1.27)
				)
				(justify mirror)
			)
		)
		(duplicate_pad_numbers_are_jumpers no)
		(fp_poly
			(pts
				(xy -0.3048 -0.1016) (xy -0.3048 0.9906) (xy 0.3048 0.9906) (xy 0.3048 -0.1016)
			)
			(stroke
				(width 0)
				(type default)
			)
			(fill no)
			(layer "B.CrtYd")
		)
		(fp_line
			(start -0.3048 0.9906)
			(end -0.3048 -0.1016)
			(stroke
				(width 0.1)
				(type default)
			)
			(layer "B.Fab")
		)
		(fp_line
			(start 0.3048 0.9906)
			(end -0.3048 0.9906)
			(stroke
				(width 0.1)
				(type default)
			)
			(layer "B.Fab")
		)
		(fp_line
			(start -0.3048 -0.1016)
			(end 0.3048 -0.1016)
			(stroke
				(width 0.1)
				(type default)
			)
			(layer "B.Fab")
		)
		(fp_line
			(start 0.3048 -0.1016)
			(end 0.3048 0.9906)
			(stroke
				(width 0.1)
				(type default)
			)
			(layer "B.Fab")
		)
		(pad "1" smd rect
			(at 0 0 90)
			(size 0.508 0.508)
			(layers "B.Cu" "B.Mask" "B.Paste")
			(net "P3V3_STBY")
		)
		(pad "2" smd rect
			(at 0 0.889 90)
			(size 0.508 0.508)
			(layers "B.Cu" "B.Mask" "B.Paste")
			(net "GND")
		)
		(zone
			(layer "B.Cu")
			(hatch none 0.5)
			(connect_pads
				(clearance 0)
			)
			(min_thickness 0.25)
			(keepout
				(tracks not_allowed)
				(vias allowed)
				(pads allowed)
				(copperpour not_allowed)
				(footprints allowed)
			)
			(placement
				(enabled no)
				(sheetname "")
			)
			(fill
				(thermal_gap 0.5)
				(thermal_bridge_width 0.5)
				(island_removal_mode 0)
			)
			(polygon
				(pts
					(xy 472.495118 -134.704074) (xy 472.495118 -135.212074) (xy 472.876118 -135.212074) (xy 472.876118 -134.704074)
				)
			)
		)
		(zone
			(layer "B.Cu")
			(hatch none 0.5)
			(connect_pads
				(clearance 0)
			)
			(min_thickness 0.25)
			(keepout
				(tracks allowed)
				(vias not_allowed)
				(pads allowed)
				(copperpour not_allowed)
				(footprints allowed)
			)
			(placement
				(enabled no)
				(sheetname "")
			)
			(fill
				(thermal_gap 0.5)
				(thermal_bridge_width 0.5)
				(island_removal_mode 0)
			)
			(polygon
				(pts
					(xy 472.876118 -134.704074) (xy 472.876118 -135.212074) (xy 472.495118 -135.212074) (xy 472.495118 -134.704074)
				)
			)
		)
	)
	(footprint ""
		(layer "B.Cu")
		(at 180.467 -65.024)
		(property "Reference" "R6P45"
			(at 0 0 0)
			(layer "B.SilkS")
			(hide yes)
			(effects
				(font
					(size 1.27 1.27)
				)
				(justify mirror)
			)
		)
		(property "Value" ""
			(at 0 0 0)
			(layer "B.Fab")
			(effects
				(font
					(size 1.27 1.27)
				)
				(justify mirror)
			)
		)
		(duplicate_pad_numbers_are_jumpers no)
		(fp_poly
			(pts
				(xy 0.2794 -0.1016) (xy -0.2794 -0.1016) (xy -0.2794 0.9906) (xy 0.2794 0.9906)
			)
			(stroke
				(width 0)
				(type default)
			)
			(fill no)
			(layer "B.CrtYd")
		)
		(fp_line
			(start -0.2794 -0.1016)
			(end 0.2794 -0.1016)
			(stroke
				(width 0.1)
				(type default)
			)
			(layer "B.Fab")
		)
		(fp_line
			(start -0.2794 0.9906)
			(end -0.2794 -0.1016)
			(stroke
				(width 0.1)
				(type default)
			)
			(layer "B.Fab")
		)
		(fp_line
			(start 0.2794 -0.1016)
			(end 0.2794 0.9906)
			(stroke
				(width 0.1)
				(type default)
			)
			(layer "B.Fab")
		)
		(fp_line
			(start 0.2794 0.9906)
			(end -0.2794 0.9906)
			(stroke
				(width 0.1)
				(type default)
			)
			(layer "B.Fab")
		)
		(pad "1" smd rect
			(at 0 0 180)
			(size 0.508 0.508)
			(layers "B.Cu" "B.Mask" "B.Paste")
			(net "IRQ_PVCCIN_CPU0_VRHOT_LVC3_R_N")
		)
		(pad "2" smd rect
			(at 0 0.889 180)
			(size 0.508 0.508)
			(layers "B.Cu" "B.Mask" "B.Paste")
			(net "IRQ_PVCCIN_CPU0_VRHOT_LVC3_N")
		)
		(zone
			(layer "B.Cu")
			(hatch none 0.5)
			(connect_pads
				(clearance 0)
			)
			(min_thickness 0.25)
			(keepout
				(tracks allowed)
				(vias not_allowed)
				(pads allowed)
				(copperpour not_allowed)
				(footprints allowed)
			)
			(placement
				(enabled no)
				(sheetname "")
			)
			(fill
				(thermal_gap 0.5)
				(thermal_bridge_width 0.5)
				(island_removal_mode 0)
			)
			(polygon
				(pts
					(xy 180.721 -64.77) (xy 180.213 -64.77) (xy 180.213 -64.389) (xy 180.721 -64.389)
				)
			)
		)
		(zone
			(layer "B.Cu")
			(hatch none 0.5)
			(connect_pads
				(clearance 0)
			)
			(min_thickness 0.25)
			(keepout
				(tracks not_allowed)
				(vias allowed)
				(pads allowed)
				(copperpour not_allowed)
				(footprints allowed)
			)
			(placement
				(enabled no)
				(sheetname "")
			)
			(fill
				(thermal_gap 0.5)
				(thermal_bridge_width 0.5)
				(island_removal_mode 0)
			)
			(polygon
				(pts
					(xy 180.721 -64.389) (xy 180.213 -64.389) (xy 180.213 -64.77) (xy 180.721 -64.77)
				)
			)
		)
	)
	(footprint ""
		(layer "B.Cu")
		(at 390.93775 -106.25455 180)
		(property "Reference" "C2N15"
			(at 0 0 0)
			(layer "B.SilkS")
			(hide yes)
			(effects
				(font
					(size 1.27 1.27)
				)
				(justify mirror)
			)
		)
		(property "Value" ""
			(at 0 0 0)
			(layer "B.Fab")
			(effects
				(font
					(size 1.27 1.27)
				)
				(justify mirror)
			)
		)
		(duplicate_pad_numbers_are_jumpers no)
		(fp_rect
			(start 0.2794 0.9144)
			(end -0.2794 -0.1143)
			(stroke
				(width 0)
				(type default)
			)
			(fill no)
			(layer "B.CrtYd")
		)
		(fp_line
			(start 0.2794 0.9144)
			(end 0.2794 -0.1143)
			(stroke
				(width 0.1)
				(type default)
			)
			(layer "B.Fab")
		)
		(fp_line
			(start 0.2794 -0.1143)
			(end -0.2794 -0.1143)
			(stroke
				(width 0.1)
				(type default)
			)
			(layer "B.Fab")
		)
		(fp_line
			(start -0.2794 0.9144)
			(end 0.2794 0.9144)
			(stroke
				(width 0.1)
				(type default)
			)
			(layer "B.Fab")
		)
		(fp_line
			(start -0.2794 -0.1143)
			(end -0.2794 0.9144)
			(stroke
				(width 0.1)
				(type default)
			)
			(layer "B.Fab")
		)
		(pad "1" smd custom
			(at 0 0 90)
			(size 0.10414 0.10414)
			(layers "B.Cu" "B.Mask" "B.Paste")
			(net "P1V8_PCH_STBY")
			(options
				(clearance outline)
				(anchor circle)
			)
			(primitives
				(gr_poly
					(pts
						(xy -0.20828 -0.08636) (xy -0.20828 0.08636) (xy -0.08636 0.20828) (xy 0.086614 0.20828) (xy 0.20828 0.086614)
						(xy 0.20828 -0.08636) (xy 0.08636 -0.20828) (xy -0.08636 -0.20828)
					)
					(width 0)
					(fill yes)
				)
			)
		)
		(pad "2" smd custom
			(at 0 0.8001 90)
			(size 0.10414 0.10414)
			(layers "B.Cu" "B.Mask" "B.Paste")
			(net "GND")
			(options
				(clearance outline)
				(anchor circle)
			)
			(primitives
				(gr_poly
					(pts
						(xy -0.20828 -0.08636) (xy -0.20828 0.08636) (xy -0.08636 0.20828) (xy 0.086614 0.20828) (xy 0.20828 0.086614)
						(xy 0.20828 -0.08636) (xy 0.08636 -0.20828) (xy -0.08636 -0.20828)
					)
					(width 0)
					(fill yes)
				)
			)
		)
		(zone
			(layer "B.Cu")
			(hatch none 0.5)
			(connect_pads
				(clearance 0)
			)
			(min_thickness 0.25)
			(keepout
				(tracks not_allowed)
				(vias allowed)
				(pads allowed)
				(copperpour not_allowed)
				(footprints allowed)
			)
			(placement
				(enabled no)
				(sheetname "")
			)
			(fill
				(thermal_gap 0.5)
				(thermal_bridge_width 0.5)
				(island_removal_mode 0)
			)
			(polygon
				(pts
					(xy 390.85012 -106.4641) (xy 390.85012 -106.8451) (xy 391.02538 -106.8451) (xy 391.025634 -106.4641)
				)
			)
		)
		(zone
			(layer "B.Cu")
			(hatch none 0.5)
			(connect_pads
				(clearance 0)
			)
			(min_thickness 0.25)
			(keepout
				(tracks allowed)
				(vias not_allowed)
				(pads allowed)
				(copperpour not_allowed)
				(footprints allowed)
			)
			(placement
				(enabled no)
				(sheetname "")
			)
			(fill
				(thermal_gap 0.5)
				(thermal_bridge_width 0.5)
				(island_removal_mode 0)
			)
			(polygon
				(pts
					(xy 390.85012 -106.4641) (xy 390.85012 -106.8451) (xy 391.02538 -106.8451) (xy 391.025634 -106.4641)
				)
			)
		)
	)
)
